(kicad_pcb
	(version 20241229)
	(generator "pcbnew")
	(generator_version "9.0")
	(general
		(thickness 1.6)
		(legacy_teardrops no)
	)
	(paper "A4")
	(title_block
		(title "OCuLink to PCIe adapter")
		(date "2025-06-18")
		(rev "1.0.0")
		(company "Antmicro Ltd")
		(comment 1 "www.antmicro.com")
		(comment 9 "footprints 17-20 of 159")
	)
	(layers
		(0 "F.Cu" signal)
		(4 "In1.Cu" signal)
		(6 "In2.Cu" signal)
		(2 "B.Cu" signal)
		(9 "F.Adhes" user "F.Adhesive")
		(11 "B.Adhes" user "B.Adhesive")
		(13 "F.Paste" user)
		(15 "B.Paste" user)
		(5 "F.SilkS" user "F.Silkscreen")
		(7 "B.SilkS" user "B.Silkscreen")
		(1 "F.Mask" user)
		(3 "B.Mask" user)
		(17 "Dwgs.User" user "User.Drawings")
		(19 "Cmts.User" user "User.Comments")
		(21 "Eco1.User" user "User.Eco1")
		(23 "Eco2.User" user "User.Eco2")
		(25 "Edge.Cuts" user)
		(27 "Margin" user)
		(31 "F.CrtYd" user "F.Courtyard")
		(29 "B.CrtYd" user "B.Courtyard")
		(35 "F.Fab" user)
		(33 "B.Fab" user)
	)
	(footprint "antmicro-footprints:R_0402_1005Metric"
		(layer "F.Cu")
		(at 152.900002 47.620001 90)
		(descr "Resistor SMD 0402")
		(tags "resistor SMD 0402")
		(property "Reference" "R27"
			(at 1.020001 5.699998 90)
			(layer "F.SilkS")
			(effects
				(font
					(size 0.7 0.7)
					(thickness 0.15)
				)
				(justify right top)
			)
		)
		(property "Value" "R_10k_0402"
			(at -1.011843 1.772046 90)
			(layer "F.Fab")
			(effects
				(font
					(size 0.7 0.7)
					(thickness 0.15)
				)
				(justify left bottom)
			)
		)
		(property "Datasheet" "https://www.bourns.com/docs/product-datasheets/cr.pdf"
			(at 0 0 90)
			(layer "F.Fab")
			(hide yes)
			(effects
				(font
					(size 1.27 1.27)
					(thickness 0.15)
				)
			)
		)
		(property "Description" "SMD Chip Resistor, 10 kohm, ± 1%, 62.5 mW, 0402 [1005 Metric], Thick Film, General Purpose"
			(at 0 0 90)
			(layer "F.Fab")
			(hide yes)
			(effects
				(font
					(size 1.27 1.27)
					(thickness 0.15)
				)
			)
		)
		(property "MPN" "CR0402-FX-1002GLF"
			(at 0 0 90)
			(unlocked yes)
			(layer "F.Fab")
			(hide yes)
			(effects
				(font
					(size 1 1)
					(thickness 0.15)
				)
			)
		)
		(property "Manufacturer" "Bourns"
			(at 0 0 90)
			(unlocked yes)
			(layer "F.Fab")
			(hide yes)
			(effects
				(font
					(size 1 1)
					(thickness 0.15)
				)
			)
		)
		(property "License" "Apache-2.0"
			(at 0 0 90)
			(unlocked yes)
			(layer "F.Fab")
			(hide yes)
			(effects
				(font
					(size 1 1)
					(thickness 0.15)
				)
			)
		)
		(property "Author" "Antmicro"
			(at 0 0 90)
			(unlocked yes)
			(layer "F.Fab")
			(hide yes)
			(effects
				(font
					(size 1 1)
					(thickness 0.15)
				)
			)
		)
		(property "Val" "10k"
			(at 0 0 90)
			(unlocked yes)
			(layer "F.Fab")
			(hide yes)
			(effects
				(font
					(size 1 1)
					(thickness 0.15)
				)
			)
		)
		(property "Tolerance" "1%"
			(at 0 0 90)
			(unlocked yes)
			(layer "F.Fab")
			(hide yes)
			(effects
				(font
					(size 1 1)
					(thickness 0.15)
				)
			)
		)
		(sheetname "/USB-PD/")
		(sheetfile "usb-pd.kicad_sch")
		(attr smd)
		(fp_rect
			(start -0.925 -0.47)
			(end 0.925 0.47)
			(stroke
				(width 0.05)
				(type default)
			)
			(fill no)
			(layer "F.CrtYd")
		)
		(fp_rect
			(start -0.5 -0.25)
			(end 0.5 0.25)
			(stroke
				(width 0.15)
				(type solid)
			)
			(fill no)
			(layer "F.Fab")
		)
		(fp_text user "Author: Antmicro"
			(at -0.95 4.169 90)
			(layer "F.Fab")
			(effects
				(font
					(size 0.7 0.7)
					(thickness 0.15)
				)
				(justify left bottom)
			)
		)
		(fp_text user "${REFERENCE}"
			(at 0 0 270)
			(layer "F.Fab")
			(effects
				(font
					(size 0.7 0.7)
					(thickness 0.15)
				)
				(justify right top)
			)
		)
		(fp_text user "License: Apache-2.0"
			(at -0.949999 5.169 90)
			(layer "F.Fab")
			(effects
				(font
					(size 0.7 0.7)
					(thickness 0.15)
				)
				(justify left bottom)
			)
		)
		(pad "1" smd roundrect
			(at -0.48 0 90)
			(size 0.59 0.64)
			(layers "F.Cu" "F.Mask" "F.Paste")
			(roundrect_rratio 0.25)
			(net 84 "Net-(Q6-G)")
			(pintype "passive")
		)
		(pad "2" smd roundrect
			(at 0.48 0 90)
			(size 0.59 0.64)
			(layers "F.Cu" "F.Mask" "F.Paste")
			(roundrect_rratio 0.25)
			(net 113 "VBUS")
			(pintype "passive")
		)
	)
	(footprint "antmicro-footprints:Conn_Molex_Nano-Fit_1x2_SMD_1054301202"
		(layer "F.Cu")
		(at 154.799001 35.729 180)
		(descr "Molex Nano-Fit Power Connectors, 105430-xx02, 2 Pins per row")
		(tags "connector Molex Nano-Fit")
		(property "Reference" "J4"
			(at 3.399001 -4.871 0)
			(layer "F.SilkS")
			(effects
				(font
					(size 0.7 0.7)
					(thickness 0.15)
				)
				(justify right top)
			)
		)
		(property "Value" "Molex_Nano-Fit_1x2_SMD_1054301202"
			(at 0 7.1 0)
			(layer "F.Fab")
			(effects
				(font
					(size 0.7 0.7)
					(thickness 0.15)
				)
				(justify right top)
			)
		)
		(property "Datasheet" "https://www.farnell.com/cad/3578051.pdf"
			(at 0 0 0)
			(layer "F.Fab")
			(hide yes)
			(effects
				(font
					(size 1.27 1.27)
					(thickness 0.15)
				)
			)
		)
		(property "Description" "Pin Header, Pitch 2.5 mm, 1 Row, 2 Contacts, Nano-Fit"
			(at 0 0 0)
			(layer "F.Fab")
			(hide yes)
			(effects
				(font
					(size 1.27 1.27)
					(thickness 0.15)
				)
			)
		)
		(property "Manufacturer" "Molex"
			(at 0 0 180)
			(unlocked yes)
			(layer "F.Fab")
			(hide yes)
			(effects
				(font
					(size 1 1)
					(thickness 0.15)
				)
			)
		)
		(property "MPN" "105430-1202"
			(at 0 0 180)
			(unlocked yes)
			(layer "F.Fab")
			(hide yes)
			(effects
				(font
					(size 1 1)
					(thickness 0.15)
				)
			)
		)
		(property "Author" "Antmicro"
			(at 0 0 180)
			(unlocked yes)
			(layer "F.Fab")
			(hide yes)
			(effects
				(font
					(size 1 1)
					(thickness 0.15)
				)
			)
		)
		(property "License" "Apache-2.0"
			(at 0 0 180)
			(unlocked yes)
			(layer "F.Fab")
			(hide yes)
			(effects
				(font
					(size 1 1)
					(thickness 0.15)
				)
			)
		)
		(sheetname "/")
		(sheetfile "oculink-to-pcie-adapter.kicad_sch")
		(attr smd)
		(fp_line
			(start 4.48 2.298)
			(end 4.48 -4.5)
			(stroke
				(width 0.15)
				(type solid)
			)
			(layer "F.SilkS")
		)
		(fp_line
			(start 4.48 2.298)
			(end 4.28 2.698)
			(stroke
				(width 0.15)
				(type solid)
			)
			(layer "F.SilkS")
		)
		(fp_line
			(start 4.48 -4.5)
			(end 2.68 -4.5)
			(stroke
				(width 0.15)
				(type solid)
			)
			(layer "F.SilkS")
		)
		(fp_line
			(start 4.28 2.698)
			(end 4.28 4.299)
			(stroke
				(width 0.15)
				(type solid)
			)
			(layer "F.SilkS")
		)
		(fp_line
			(start -0.22 -4.5)
			(end 0.78 -4.5)
			(stroke
				(width 0.15)
				(type solid)
			)
			(layer "F.SilkS")
		)
		(fp_line
			(start -1.72 -4.5)
			(end -4.47 -4.5)
			(stroke
				(width 0.15)
				(type solid)
			)
			(layer "F.SilkS")
		)
		(fp_line
			(start -4.321 4.299)
			(end 4.28 4.299)
			(stroke
				(width 0.15)
				(type solid)
			)
			(layer "F.SilkS")
		)
		(fp_line
			(start -4.321 2.499)
			(end -4.321 4.299)
			(stroke
				(width 0.15)
				(type solid)
			)
			(layer "F.SilkS")
		)
		(fp_line
			(start -4.47 2.099)
			(end -4.321 2.499)
			(stroke
				(width 0.15)
				(type solid)
			)
			(layer "F.SilkS")
		)
		(fp_line
			(start -4.47 -4.5)
			(end -4.47 2.099)
			(stroke
				(width 0.15)
				(type solid)
			)
			(layer "F.SilkS")
		)
		(fp_circle
			(center 2.428 -4.91)
			(end 2.478 -4.91)
			(stroke
				(width 0.15)
				(type solid)
			)
			(fill yes)
			(layer "F.SilkS")
		)
		(fp_rect
			(start -4.77 -6.21)
			(end 4.77 6.11)
			(stroke
				(width 0.05)
				(type solid)
			)
			(fill no)
			(layer "F.CrtYd")
		)
		(fp_text user "License: Apache-2.0"
			(at -4.77 10.51 0)
			(layer "F.Fab")
			(effects
				(font
					(size 0.7 0.7)
					(thickness 0.15)
				)
				(justify right top)
			)
		)
		(fp_text user "Author: Antmicro"
			(at -4.77 9.31 0)
			(layer "F.Fab")
			(effects
				(font
					(size 0.7 0.7)
					(thickness 0.15)
				)
				(justify right top)
			)
		)
		(fp_text user "${REFERENCE}"
			(at -4.77 8.11 0)
			(layer "F.Fab")
			(effects
				(font
					(size 0.7 0.7)
					(thickness 0.15)
				)
				(justify right top)
			)
		)
		(pad "1" smd roundrect
			(at 1.528 -4.901 270)
			(size 2.5 1.24)
			(layers "F.Cu" "F.Mask" "F.Paste")
			(roundrect_rratio 0.25)
			(net 168 "/Power/VCC_DC_CONN_1")
			(pintype "passive")
		)
		(pad "2" smd roundrect
			(at -0.97 -4.901 270)
			(size 2.5 1.24)
			(layers "F.Cu" "F.Mask" "F.Paste")
			(roundrect_rratio 0.25)
			(net 66 "GND")
			(pintype "passive")
		)
		(pad "MP" smd roundrect
			(at -3.54 0.029 180)
			(size 1.1 8.2)
			(layers "F.Cu" "F.Mask" "F.Paste")
			(roundrect_rratio 0.25)
			(net 66 "GND")
			(pintype "passive")
		)
		(pad "MP" smd roundrect
			(at 3.499 0.029 180)
			(size 1.1 8.2)
			(layers "F.Cu" "F.Mask" "F.Paste")
			(roundrect_rratio 0.25)
			(net 66 "GND")
			(pintype "passive")
		)
	)
	(footprint "antmicro-footprints:USON-10_2.5x1mm_P0.5mm"
		(layer "F.Cu")
		(at 130.298 43.387 -90)
		(descr "USON-10 2.5x1mm_ Pitch 0.5mm")
		(tags "USON-10 2.5x1mm Pitch 0.5mm")
		(property "Reference" "D5"
			(at 1.113 -0.702 180)
			(layer "F.SilkS")
			(effects
				(font
					(size 0.7 0.7)
					(thickness 0.15)
				)
				(justify right top)
			)
		)
		(property "Value" "ESD204DQAR"
			(at 0.018 2.499 90)
			(layer "F.Fab")
			(effects
				(font
					(size 0.7 0.7)
					(thickness 0.15)
				)
				(justify right top)
			)
		)
		(property "Datasheet" "https://www.ti.com/lit/ds/symlink/esd204.pdf?ts=1706004844383&ref_url=https%253A%252F%252Fwww.ti.com%252Finterface%252Fdiodes%252Fesd-protection-diodes%252Fproducts.html"
			(at 0 0 90)
			(layer "F.Fab")
			(hide yes)
			(effects
				(font
					(size 1.27 1.27)
					(thickness 0.15)
				)
			)
		)
		(property "Description" "TVS diode array, 30 kV, USON-10, 3.6 V, 0.55 pF"
			(at 0 0 90)
			(layer "F.Fab")
			(hide yes)
			(effects
				(font
					(size 1.27 1.27)
					(thickness 0.15)
				)
			)
		)
		(property "MPN" "ESD204DQAR"
			(at 0 0 270)
			(unlocked yes)
			(layer "F.Fab")
			(hide yes)
			(effects
				(font
					(size 1 1)
					(thickness 0.15)
				)
			)
		)
		(property "Manufacturer" "Texas Instruments"
			(at 0 0 270)
			(unlocked yes)
			(layer "F.Fab")
			(hide yes)
			(effects
				(font
					(size 1 1)
					(thickness 0.15)
				)
			)
		)
		(property "Author" "Antmicro"
			(at 0 0 270)
			(unlocked yes)
			(layer "F.Fab")
			(hide yes)
			(effects
				(font
					(size 1 1)
					(thickness 0.15)
				)
			)
		)
		(property "License" "Apache-2.0"
			(at 0 0 270)
			(unlocked yes)
			(layer "F.Fab")
			(hide yes)
			(effects
				(font
					(size 1 1)
					(thickness 0.15)
				)
			)
		)
		(sheetname "/OCuLink/")
		(sheetfile "oculink.kicad_sch")
		(attr smd)
		(fp_line
			(start 0.498 1.398)
			(end -0.5 1.398)
			(stroke
				(width 0.15)
				(type solid)
			)
			(layer "F.SilkS")
		)
		(fp_line
			(start 0.498 -1.401)
			(end -0.5 -1.401)
			(stroke
				(width 0.15)
				(type solid)
			)
			(layer "F.SilkS")
		)
		(fp_circle
			(center -0.68 -1.27)
			(end -0.63 -1.27)
			(stroke
				(width 0.15)
				(type solid)
			)
			(fill yes)
			(layer "F.SilkS")
		)
		(fp_rect
			(start -0.8 -1.5)
			(end 0.8 1.499)
			(stroke
				(width 0.05)
				(type solid)
			)
			(fill no)
			(layer "F.CrtYd")
		)
		(fp_line
			(start -0.5 1.249)
			(end 0.498 1.249)
			(stroke
				(width 0.15)
				(type solid)
			)
			(layer "F.Fab")
		)
		(fp_line
			(start -0.5 -1)
			(end -0.5 1.249)
			(stroke
				(width 0.15)
				(type solid)
			)
			(layer "F.Fab")
		)
		(fp_line
			(start -0.25 -1.25)
			(end -0.5 -1)
			(stroke
				(width 0.15)
				(type solid)
			)
			(layer "F.Fab")
		)
		(fp_line
			(start 0.498 -1.25)
			(end 0.498 1.249)
			(stroke
				(width 0.15)
				(type solid)
			)
			(layer "F.Fab")
		)
		(fp_line
			(start 0.498 -1.25)
			(end -0.25 -1.25)
			(stroke
				(width 0.15)
				(type solid)
			)
			(layer "F.Fab")
		)
		(fp_text user "License: Apache-2.0"
			(at -0.802 6.9 90)
			(layer "F.Fab")
			(effects
				(font
					(size 0.7 0.7)
					(thickness 0.15)
				)
				(justify right top)
			)
		)
		(fp_text user "${REFERENCE}"
			(at 0 -0.000501 90)
			(layer "F.Fab")
			(effects
				(font
					(size 0.7 0.7)
					(thickness 0.15)
				)
				(justify right top)
			)
		)
		(fp_text user "Author: Antmicro"
			(at -0.802 5.7 90)
			(layer "F.Fab")
			(effects
				(font
					(size 0.7 0.7)
					(thickness 0.15)
				)
				(justify right top)
			)
		)
		(pad "1" smd roundrect
			(at -0.387 -1 180)
			(size 0.25 0.55)
			(layers "F.Cu" "F.Mask" "F.Paste")
			(roundrect_rratio 0.25)
			(net 78 "/OCuLink/PCIe_{x4}.RX0+")
			(pintype "passive")
		)
		(pad "2" smd roundrect
			(at -0.387 -0.5 180)
			(size 0.25 0.55)
			(layers "F.Cu" "F.Mask" "F.Paste")
			(roundrect_rratio 0.25)
			(net 73 "/OCuLink/PCIe_{x4}.RX0-")
			(pintype "passive")
		)
		(pad "3" smd roundrect
			(at -0.387 0 180)
			(size 0.4 0.55)
			(layers "F.Cu" "F.Mask" "F.Paste")
			(roundrect_rratio 0.25)
			(net 66 "GND")
			(pintype "power_in")
		)
		(pad "4" smd roundrect
			(at -0.387 0.498 180)
			(size 0.25 0.55)
			(layers "F.Cu" "F.Mask" "F.Paste")
			(roundrect_rratio 0.25)
			(net 75 "/OCuLink/PCIe_{x4}.RX1+")
			(pintype "passive")
		)
		(pad "5" smd roundrect
			(at -0.387 0.998 180)
			(size 0.25 0.55)
			(layers "F.Cu" "F.Mask" "F.Paste")
			(roundrect_rratio 0.25)
			(net 71 "/OCuLink/PCIe_{x4}.RX1-")
			(pintype "passive")
		)
		(pad "6" smd roundrect
			(at 0.385 0.998 180)
			(size 0.25 0.55)
			(layers "F.Cu" "F.Mask" "F.Paste")
			(roundrect_rratio 0.25)
			(net 71 "/OCuLink/PCIe_{x4}.RX1-")
			(pintype "passive")
		)
		(pad "7" smd roundrect
			(at 0.385 0.498 180)
			(size 0.25 0.55)
			(layers "F.Cu" "F.Mask" "F.Paste")
			(roundrect_rratio 0.25)
			(net 75 "/OCuLink/PCIe_{x4}.RX1+")
			(pintype "passive")
		)
		(pad "8" smd roundrect
			(at 0.385 0 180)
			(size 0.4 0.55)
			(layers "F.Cu" "F.Mask" "F.Paste")
			(roundrect_rratio 0.25)
			(net 66 "GND")
			(pintype "passive")
		)
		(pad "9" smd roundrect
			(at 0.385 -0.5 180)
			(size 0.25 0.55)
			(layers "F.Cu" "F.Mask" "F.Paste")
			(roundrect_rratio 0.25)
			(net 73 "/OCuLink/PCIe_{x4}.RX0-")
			(pintype "passive")
		)
		(pad "10" smd roundrect
			(at 0.385 -1 180)
			(size 0.25 0.55)
			(layers "F.Cu" "F.Mask" "F.Paste")
			(roundrect_rratio 0.25)
			(net 78 "/OCuLink/PCIe_{x4}.RX0+")
			(pintype "passive")
		)
	)
	(footprint "antmicro-footprints:C_0402_1005Metric"
		(layer "F.Cu")
		(at 146.562001 52.001)
		(descr "Capacitor SMD 0402")
		(tags "capacitor SMD 0402")
		(property "Reference" "C39"
			(at -3.162001 2.899 180)
			(layer "F.SilkS")
			(effects
				(font
					(size 0.7 0.7)
					(thickness 0.15)
				)
				(justify left bottom)
			)
		)
		(property "Value" "C_1u_25V_0402"
			(at -1.022927 2.155213 0)
			(layer "F.Fab")
			(effects
				(font
					(size 0.7 0.7)
					(thickness 0.15)
				)
				(justify left bottom)
			)
		)
		(property "Datasheet" "https://www.murata.com/products/productdetail?partno=GRM155R61E105KE11%23"
			(at 0 0 0)
			(layer "F.Fab")
			(hide yes)
			(effects
				(font
					(size 1.27 1.27)
					(thickness 0.15)
				)
			)
		)
		(property "Description" "SMD Multilayer Ceramic Capacitor, 1 µF, 25 V, 0402 [1005 Metric], ± 10%, X5R, GRM Series"
			(at 0 0 0)
			(layer "F.Fab")
			(hide yes)
			(effects
				(font
					(size 1.27 1.27)
					(thickness 0.15)
				)
			)
		)
		(property "MPN" "GRM155R61E105KE11J"
			(at 0 0 0)
			(unlocked yes)
			(layer "F.Fab")
			(hide yes)
			(effects
				(font
					(size 1 1)
					(thickness 0.15)
				)
			)
		)
		(property "Manufacturer" "Murata"
			(at 0 0 0)
			(unlocked yes)
			(layer "F.Fab")
			(hide yes)
			(effects
				(font
					(size 1 1)
					(thickness 0.15)
				)
			)
		)
		(property "License" "Apache-2.0"
			(at 0 0 0)
			(unlocked yes)
			(layer "F.Fab")
			(hide yes)
			(effects
				(font
					(size 1 1)
					(thickness 0.15)
				)
			)
		)
		(property "Author" "Antmicro"
			(at 0 0 0)
			(unlocked yes)
			(layer "F.Fab")
			(hide yes)
			(effects
				(font
					(size 1 1)
					(thickness 0.15)
				)
			)
		)
		(property "Val" "1u"
			(at 0 0 0)
			(unlocked yes)
			(layer "F.Fab")
			(hide yes)
			(effects
				(font
					(size 1 1)
					(thickness 0.15)
				)
			)
		)
		(property "Voltage" "25V"
			(at 0 0 0)
			(unlocked yes)
			(layer "F.Fab")
			(hide yes)
			(effects
				(font
					(size 1 1)
					(thickness 0.15)
				)
			)
		)
		(property "Dielectric" "X5R"
			(at 0 0 0)
			(unlocked yes)
			(layer "F.Fab")
			(hide yes)
			(effects
				(font
					(size 1 1)
					(thickness 0.15)
				)
			)
		)
		(sheetname "/USB-PD/")
		(sheetfile "usb-pd.kicad_sch")
		(attr smd)
		(fp_rect
			(start -0.925 -0.47)
			(end 0.925 0.47)
			(stroke
				(width 0.05)
				(type default)
			)
			(fill no)
			(layer "F.CrtYd")
		)
		(fp_line
			(start -0.494 -0.25)
			(end 0.504 -0.25)
			(stroke
				(width 0.15)
				(type solid)
			)
			(layer "F.Fab")
		)
		(fp_line
			(start -0.494 0.248)
			(end -0.494 -0.25)
			(stroke
				(width 0.15)
				(type solid)
			)
			(layer "F.Fab")
		)
		(fp_line
			(start 0.504 -0.25)
			(end 0.504 0.248)
			(stroke
				(width 0.15)
				(type solid)
			)
			(layer "F.Fab")
		)
		(fp_line
			(start 0.504 0.248)
			(end -0.494 0.248)
			(stroke
				(width 0.15)
				(type solid)
			)
			(layer "F.Fab")
		)
		(fp_text user "${REFERENCE}"
			(at 0 0 0)
			(layer "F.Fab")
			(effects
				(font
					(size 0.7 0.7)
					(thickness 0.15)
				)
				(justify left bottom)
			)
		)
		(fp_text user "Author: Antmicro"
			(at -0.939 3.399 0)
			(layer "F.Fab")
			(effects
				(font
					(size 0.7 0.7)
					(thickness 0.15)
				)
				(justify left bottom)
			)
		)
		(fp_text user "License: Apache-2.0"
			(at -0.939 5.799 0)
			(layer "F.Fab")
			(effects
				(font
					(size 0.7 0.7)
					(thickness 0.15)
				)
				(justify left bottom)
			)
		)
		(pad "1" smd roundrect
			(at -0.48 0)
			(size 0.59 0.64)
			(layers "F.Cu" "F.Mask" "F.Paste")
			(roundrect_rratio 0.25)
			(net 66 "GND")
			(pintype "passive")
		)
		(pad "2" smd roundrect
			(at 0.48 0)
			(size 0.59 0.64)
			(layers "F.Cu" "F.Mask" "F.Paste")
			(roundrect_rratio 0.25)
			(net 117 "/USB-PD/VDDD_3V3")
			(pintype "passive")
		)
	)
)
